# S9S_MB_2U (Grand Teton) — schematic netlist excerpt (pin names and nets, part order shuffled) for the footprints in the layout excerpt that follows; sources: Cadence DE-HDL packaged netlist, KiCad conversion of 03242023_DA0F0TMBIJ0_F0T_Motherboard_J_brd_V01_OCP.brd

PR318  Q_RES  5.23K 1% CHIP  pkg 0402LF  page 284 : A = PVCCIN_CPU1_ADDR ; B = GND
R37  Q_RES  35.7K 1% CHIP  pkg 0402LF  page 93 : A = PD_CHF_CPU0_DIMM2_SAA ; B = GND

(kicad_pcb
	(version 20260206)
	(generator "pcbnew")
	(generator_version "10.0")
	(general
		(thickness 1.6)
		(legacy_teardrops no)
	)
	(paper "A4")
	(title_block
		(title "03242023_DA0F0TMBIJ0_F0T_Motherboard_J_brd_V01_OCP.brd")
		(comment 1 "Grand Teton / footprints 4172-4173 of 6105")
	)
	(layers
		(0 "F.Cu" signal "TOP")
		(4 "In1.Cu" signal "GND")
		(6 "In2.Cu" signal "IN1")
		(8 "In3.Cu" signal "GND1")
		(10 "In4.Cu" signal "IN2")
		(12 "In5.Cu" signal "GND2")
		(14 "In6.Cu" signal "IN3")
		(16 "In7.Cu" signal "GND3")
		(18 "In8.Cu" signal "VCC")
		(20 "In9.Cu" signal "VCC1")
		(22 "In10.Cu" signal "GND4")
		(24 "In11.Cu" signal "IN4")
		(26 "In12.Cu" signal "GND5")
		(28 "In13.Cu" signal "IN5")
		(30 "In14.Cu" signal "GND6")
		(32 "In15.Cu" signal "IN6")
		(34 "In16.Cu" signal "GND7")
		(2 "B.Cu" signal "BOTTOM")
		(9 "F.Adhes" user "F.Adhesive")
		(11 "B.Adhes" user "B.Adhesive")
		(13 "F.Paste" user "Package Geometry/Pastemask Top")
		(15 "B.Paste" user "Package Geometry/Pastemask Bottom")
		(5 "F.SilkS" user "Ref Des/Silkscreen Top")
		(7 "B.SilkS" user "Ref Des/Silkscreen Bottom")
		(1 "F.Mask" user "Board Geometry/Soldermask Top")
		(3 "B.Mask" user "Board Geometry/Soldermask Bottom")
		(17 "Dwgs.User" user "User.Drawings")
		(19 "Cmts.User" user "User.Comments")
		(21 "Eco1.User" user "User.Eco1")
		(23 "Eco2.User" user "User.Eco2")
		(25 "Edge.Cuts" user "Board Geometry/Outline")
		(27 "Margin" user)
		(31 "F.CrtYd" user "Package Geometry/Place Bound Top")
		(29 "B.CrtYd" user "Package Geometry/Place Bound Bottom")
		(35 "F.Fab" user "Ref Des/Assembly Top")
		(33 "B.Fab" user "Ref Des/Assembly Bottom")
	)
	(footprint ""
		(layer "B.Cu")
		(at 423.650156 -318.781176)
		(property "Reference" "R37"
			(at 0 0 0)
			(layer "B.SilkS")
			(hide yes)
			(effects
				(font
					(size 1.27 1.27)
				)
				(justify mirror)
			)
		)
		(property "Value" ""
			(at 0 0 0)
			(layer "B.Fab")
			(effects
				(font
					(size 1.27 1.27)
				)
				(justify mirror)
			)
		)
		(duplicate_pad_numbers_are_jumpers no)
		(fp_line
			(start -0.7874 -0.4064)
			(end -0.7874 0.4064)
			(stroke
				(width 0.1524)
				(type default)
			)
			(layer "B.SilkS")
		)
		(fp_line
			(start -0.7874 0.4064)
			(end 0.7874 0.4064)
			(stroke
				(width 0.1524)
				(type default)
			)
			(layer "B.SilkS")
		)
		(fp_line
			(start 0.7874 -0.4064)
			(end -0.7874 -0.4064)
			(stroke
				(width 0.1524)
				(type default)
			)
			(layer "B.SilkS")
		)
		(fp_line
			(start 0.7874 0.4064)
			(end 0.7874 -0.4064)
			(stroke
				(width 0.1524)
				(type default)
			)
			(layer "B.SilkS")
		)
		(fp_line
			(start -0.67945 -0.3048)
			(end -0.67945 0.3048)
			(stroke
				(width 0.1)
				(type default)
			)
			(layer "B.Fab")
		)
		(fp_line
			(start -0.67945 0.3048)
			(end -0.120396 0.3048)
			(stroke
				(width 0.1)
				(type default)
			)
			(layer "B.Fab")
		)
		(fp_line
			(start -0.12065 -0.3048)
			(end -0.67945 -0.3048)
			(stroke
				(width 0.1)
				(type default)
			)
			(layer "B.Fab")
		)
		(fp_line
			(start -0.12065 -0.2794)
			(end -0.12065 -0.3048)
			(stroke
				(width 0.1)
				(type default)
			)
			(layer "B.Fab")
		)
		(fp_line
			(start -0.120396 0.2794)
			(end 0.12065 0.2794)
			(stroke
				(width 0.1)
				(type default)
			)
			(layer "B.Fab")
		)
		(fp_line
			(start -0.120396 0.3048)
			(end -0.120396 0.2794)
			(stroke
				(width 0.1)
				(type default)
			)
			(layer "B.Fab")
		)
		(fp_line
			(start 0.12065 -0.305054)
			(end 0.12065 -0.2794)
			(stroke
				(width 0.1)
				(type default)
			)
			(layer "B.Fab")
		)
		(fp_line
			(start 0.12065 -0.2794)
			(end -0.12065 -0.2794)
			(stroke
				(width 0.1)
				(type default)
			)
			(layer "B.Fab")
		)
		(fp_line
			(start 0.12065 0.2794)
			(end 0.12065 0.3048)
			(stroke
				(width 0.1)
				(type default)
			)
			(layer "B.Fab")
		)
		(fp_line
			(start 0.12065 0.3048)
			(end 0.67945 0.3048)
			(stroke
				(width 0.1)
				(type default)
			)
			(layer "B.Fab")
		)
		(fp_line
			(start 0.67945 -0.305054)
			(end 0.12065 -0.305054)
			(stroke
				(width 0.1)
				(type default)
			)
			(layer "B.Fab")
		)
		(fp_line
			(start 0.67945 0.3048)
			(end 0.67945 -0.305054)
			(stroke
				(width 0.1)
				(type default)
			)
			(layer "B.Fab")
		)
		(pad "1" smd circle
			(at 0.40005 0 180)
			(size 0 0)
			(layers "B.Cu" "B.Mask" "B.Paste")
			(net "PD_CHF_CPU0_DIMM2_SAA")
		)
		(pad "2" smd circle
			(at -0.40005 0 180)
			(size 0 0)
			(layers "B.Cu" "B.Mask" "B.Paste")
			(net "GND")
		)
	)
	(footprint ""
		(layer "B.Cu")
		(at 110.864396 -357.578406)
		(property "Reference" "PR318"
			(at 0 0 0)
			(layer "B.SilkS")
			(hide yes)
			(effects
				(font
					(size 1.27 1.27)
				)
				(justify mirror)
			)
		)
		(property "Value" ""
			(at 0 0 0)
			(layer "B.Fab")
			(effects
				(font
					(size 1.27 1.27)
				)
				(justify mirror)
			)
		)
		(duplicate_pad_numbers_are_jumpers no)
		(fp_line
			(start -0.7874 -0.4064)
			(end -0.7874 0.4064)
			(stroke
				(width 0.1524)
				(type default)
			)
			(layer "B.SilkS")
		)
		(fp_line
			(start -0.7874 0.4064)
			(end 0.7874 0.4064)
			(stroke
				(width 0.1524)
				(type default)
			)
			(layer "B.SilkS")
		)
		(fp_line
			(start 0.7874 -0.4064)
			(end -0.7874 -0.4064)
			(stroke
				(width 0.1524)
				(type default)
			)
			(layer "B.SilkS")
		)
		(fp_line
			(start 0.7874 0.4064)
			(end 0.7874 -0.4064)
			(stroke
				(width 0.1524)
				(type default)
			)
			(layer "B.SilkS")
		)
		(fp_line
			(start -0.67945 -0.3048)
			(end -0.67945 0.3048)
			(stroke
				(width 0.1)
				(type default)
			)
			(layer "B.Fab")
		)
		(fp_line
			(start -0.67945 0.3048)
			(end -0.120396 0.3048)
			(stroke
				(width 0.1)
				(type default)
			)
			(layer "B.Fab")
		)
		(fp_line
			(start -0.12065 -0.3048)
			(end -0.67945 -0.3048)
			(stroke
				(width 0.1)
				(type default)
			)
			(layer "B.Fab")
		)
		(fp_line
			(start -0.12065 -0.2794)
			(end -0.12065 -0.3048)
			(stroke
				(width 0.1)
				(type default)
			)
			(layer "B.Fab")
		)
		(fp_line
			(start -0.120396 0.2794)
			(end 0.12065 0.2794)
			(stroke
				(width 0.1)
				(type default)
			)
			(layer "B.Fab")
		)
		(fp_line
			(start -0.120396 0.3048)
			(end -0.120396 0.2794)
			(stroke
				(width 0.1)
				(type default)
			)
			(layer "B.Fab")
		)
		(fp_line
			(start 0.12065 -0.305054)
			(end 0.12065 -0.2794)
			(stroke
				(width 0.1)
				(type default)
			)
			(layer "B.Fab")
		)
		(fp_line
			(start 0.12065 -0.2794)
			(end -0.12065 -0.2794)
			(stroke
				(width 0.1)
				(type default)
			)
			(layer "B.Fab")
		)
		(fp_line
			(start 0.12065 0.2794)
			(end 0.12065 0.3048)
			(stroke
				(width 0.1)
				(type default)
			)
			(layer "B.Fab")
		)
		(fp_line
			(start 0.12065 0.3048)
			(end 0.67945 0.3048)
			(stroke
				(width 0.1)
				(type default)
			)
			(layer "B.Fab")
		)
		(fp_line
			(start 0.67945 -0.305054)
			(end 0.12065 -0.305054)
			(stroke
				(width 0.1)
				(type default)
			)
			(layer "B.Fab")
		)
		(fp_line
			(start 0.67945 0.3048)
			(end 0.67945 -0.305054)
			(stroke
				(width 0.1)
				(type default)
			)
			(layer "B.Fab")
		)
		(pad "1" smd circle
			(at 0.40005 0 180)
			(size 0 0)
			(layers "B.Cu" "B.Mask" "B.Paste")
			(net "PVCCIN_CPU1_ADDR")
		)
		(pad "2" smd circle
			(at -0.40005 0 180)
			(size 0 0)
			(layers "B.Cu" "B.Mask" "B.Paste")
			(net "GND")
		)
	)
)
